(kicad_pcb
	(version 20241229)
	(generator "pcbnew")
	(generator_version "9.0")
	(general
		(thickness 1.294)
		(legacy_teardrops no)
	)
	(paper "A3")
	(title_block
		(title "Kintex 410T devboard")
		(date "2024-04-03")
		(rev "1.1.2")
		(comment 9 "footprint 170 of 975 (U1), pads 476-536 of 900")
	)
	(layers
		(0 "F.Cu" mixed)
		(4 "In1.Cu" power)
		(6 "In2.Cu" power)
		(8 "In3.Cu" mixed)
		(10 "In4.Cu" power)
		(12 "In5.Cu" mixed)
		(14 "In6.Cu" power)
		(16 "In7.Cu" mixed)
		(18 "In8.Cu" power)
		(2 "B.Cu" mixed)
		(9 "F.Adhes" user "F.Adhesive")
		(11 "B.Adhes" user "B.Adhesive")
		(13 "F.Paste" user)
		(15 "B.Paste" user)
		(5 "F.SilkS" user "F.Silkscreen")
		(7 "B.SilkS" user "B.Silkscreen")
		(1 "F.Mask" user)
		(3 "B.Mask" user)
		(17 "Dwgs.User" user "User.Drawings")
		(19 "Cmts.User" user "User.Comments")
		(21 "Eco1.User" user "User.Eco1")
		(23 "Eco2.User" user "User.Eco2")
		(25 "Edge.Cuts" user)
		(27 "Margin" user)
		(31 "F.CrtYd" user "F.Courtyard")
		(29 "B.CrtYd" user "B.Courtyard")
		(35 "F.Fab" user)
		(33 "B.Fab" user)
	)
	(footprint "antmicro-footprints:BGA-900_31x31mm_Layout30x30_P1x1mm_FFG900"
		(locked yes)
		(layer "F.Cu")
		(at 200 130)
		(property "Reference" "U1"
			(at -15.74 -15.78 0)
			(layer "F.SilkS")
			(effects
				(font
					(size 0.7 0.7)
					(thickness 0.15)
				)
				(justify left bottom)
			)
		)
		(property "Value" "XC7K410T-2FFG900I"
			(at -4.436 17.635 0)
			(layer "F.Fab")
			(effects
				(font
					(size 0.7 0.7)
					(thickness 0.15)
				)
				(justify left bottom)
			)
		)
		(property "Description" "FPGA, Kintex-7, MMCM, PLL, 350 I/O's, 710 MHz, 406720 Cells, 970 mV to 1.03 V, FCBGA-900"
			(at 0 0 0)
			(layer "F.Fab")
			(hide yes)
			(effects
				(font
					(size 1.27 1.27)
					(thickness 0.15)
				)
			)
		)
		(property "Author" "Antmicro"
			(at 0 0 0)
			(layer "F.Fab")
			(hide yes)
			(effects
				(font
					(size 1 1)
					(thickness 0.15)
				)
			)
		)
		(property "License" "Apache-2.0"
			(at 0 0 0)
			(layer "F.Fab")
			(hide yes)
			(effects
				(font
					(size 1 1)
					(thickness 0.15)
				)
			)
		)
		(property "MPN" "XC7K410T-2FFG900I"
			(at 0 0 0)
			(layer "F.Fab")
			(hide yes)
			(effects
				(font
					(size 1 1)
					(thickness 0.15)
				)
			)
		)
		(property "Manufacturer" "AMD-Xilinx"
			(at 0 0 0)
			(layer "F.Fab")
			(hide yes)
			(effects
				(font
					(size 1 1)
					(thickness 0.15)
				)
			)
		)
		(sheetname "FPGA supply")
		(sheetfile "fpga-supply.kicad_sch")
		(attr smd)
		(pad "F26" smd circle
			(at 10.5 -9.5)
			(size 0.5 0.5)
			(property pad_prop_bga)
			(layers "F.Cu" "F.Mask" "F.Paste")
			(net 981 "unconnected-(U1C-IO_L5P_T0_16-PadF26)")
			(pinfunction "IO_L5P_T0_16")
			(pintype "bidirectional+no_connect")
			(die_length 17.252)
			(solder_mask_margin 0.02)
		)
		(pad "F27" smd circle
			(at 11.5 -9.5)
			(size 0.5 0.5)
			(property pad_prop_bga)
			(layers "F.Cu" "F.Mask" "F.Paste")
			(net 1291 "/USER_IO.B31")
			(pinfunction "IO_L21N_T3_DQS_16")
			(pintype "bidirectional")
			(die_length 19.729)
			(solder_mask_margin 0.02)
		)
		(pad "F28" smd circle
			(at 12.5 -9.5)
			(size 0.5 0.5)
			(property pad_prop_bga)
			(layers "F.Cu" "F.Mask" "F.Paste")
			(net 1282 "/USER_IO.B21")
			(pinfunction "IO_L20N_T3_16")
			(pintype "bidirectional")
			(die_length 20.204)
			(solder_mask_margin 0.02)
		)
		(pad "F29" smd circle
			(at 13.5 -9.5)
			(size 0.5 0.5)
			(property pad_prop_bga)
			(layers "F.Cu" "F.Mask" "F.Paste")
			(net 1 "GND")
			(pinfunction "GND")
			(pintype "passive")
			(solder_mask_margin 0.02)
		)
		(pad "F30" smd circle
			(at 14.5 -9.5)
			(size 0.5 0.5)
			(property pad_prop_bga)
			(layers "F.Cu" "F.Mask" "F.Paste")
			(net 1281 "/USER_IO.B19")
			(pinfunction "IO_L22N_T3_16")
			(pintype "bidirectional")
			(die_length 20.812)
			(solder_mask_margin 0.02)
		)
		(pad "G1" smd circle
			(at -14.5 -8.5)
			(size 0.5 0.5)
			(property pad_prop_bga)
			(layers "F.Cu" "F.Mask" "F.Paste")
			(net 1 "GND")
			(pinfunction "GND")
			(pintype "passive")
			(solder_mask_margin 0.02)
		)
		(pad "G2" smd circle
			(at -13.5 -8.5)
			(size 0.5 0.5)
			(property pad_prop_bga)
			(layers "F.Cu" "F.Mask" "F.Paste")
			(net 1 "GND")
			(pinfunction "GND")
			(pintype "passive")
			(solder_mask_margin 0.02)
		)
		(pad "G3" smd circle
			(at -12.5 -8.5)
			(size 0.5 0.5)
			(property pad_prop_bga)
			(layers "F.Cu" "F.Mask" "F.Paste")
			(net 1004 "unconnected-(U1G-MGTXRXN2_117-PadG3)")
			(pinfunction "MGTXRXN2_117")
			(pintype "bidirectional+no_connect")
			(die_length 12.896)
			(solder_mask_margin 0.02)
		)
		(pad "G4" smd circle
			(at -11.5 -8.5)
			(size 0.5 0.5)
			(property pad_prop_bga)
			(layers "F.Cu" "F.Mask" "F.Paste")
			(net 1005 "unconnected-(U1G-MGTXRXP2_117-PadG4)")
			(pinfunction "MGTXRXP2_117")
			(pintype "bidirectional+no_connect")
			(die_length 12.853)
			(solder_mask_margin 0.02)
		)
		(pad "G5" smd circle
			(at -10.5 -8.5)
			(size 0.5 0.5)
			(property pad_prop_bga)
			(layers "F.Cu" "F.Mask" "F.Paste")
			(net 8 "+1V2_MGTAVTT")
			(pinfunction "MGTAVTT")
			(pintype "passive")
			(solder_mask_margin 0.02)
		)
		(pad "G6" smd circle
			(at -9.5 -8.5)
			(size 0.5 0.5)
			(property pad_prop_bga)
			(layers "F.Cu" "F.Mask" "F.Paste")
			(net 1 "GND")
			(pinfunction "GND")
			(pintype "passive")
			(solder_mask_margin 0.02)
		)
		(pad "G7" smd circle
			(at -8.5 -8.5)
			(size 0.5 0.5)
			(property pad_prop_bga)
			(layers "F.Cu" "F.Mask" "F.Paste")
			(net 1006 "unconnected-(U1G-MGTREFCLK0N_117-PadG7)")
			(pinfunction "MGTREFCLK0N_117")
			(pintype "bidirectional+no_connect")
			(die_length 10.176)
			(solder_mask_margin 0.02)
		)
		(pad "G8" smd circle
			(at -7.5 -8.5)
			(size 0.5 0.5)
			(property pad_prop_bga)
			(layers "F.Cu" "F.Mask" "F.Paste")
			(net 1007 "unconnected-(U1G-MGTREFCLK0P_117-PadG8)")
			(pinfunction "MGTREFCLK0P_117")
			(pintype "bidirectional+no_connect")
			(die_length 9.73)
			(solder_mask_margin 0.02)
		)
		(pad "G9" smd circle
			(at -6.5 -8.5)
			(size 0.5 0.5)
			(property pad_prop_bga)
			(layers "F.Cu" "F.Mask" "F.Paste")
			(net 1 "GND")
			(pinfunction "GND")
			(pintype "passive")
			(solder_mask_margin 0.02)
		)
		(pad "G10" smd circle
			(at -5.5 -8.5)
			(size 0.5 0.5)
			(property pad_prop_bga)
			(layers "F.Cu" "F.Mask" "F.Paste")
			(net 190 "/FPGA Config/JTAG.TDO")
			(pinfunction "TDO_0")
			(pintype "bidirectional")
			(die_length 23.572)
			(solder_mask_margin 0.02)
		)
		(pad "G11" smd circle
			(at -4.5 -8.5)
			(size 0.5 0.5)
			(property pad_prop_bga)
			(layers "F.Cu" "F.Mask" "F.Paste")
			(net 24 "+3V3")
			(pinfunction "VCCO_18")
			(pintype "passive")
			(solder_mask_margin 0.02)
		)
		(pad "G12" smd circle
			(at -3.5 -8.5)
			(size 0.5 0.5)
			(property pad_prop_bga)
			(layers "F.Cu" "F.Mask" "F.Paste")
			(net 373 "/FMC+ HSPC/FMC.IO0")
			(pinfunction "IO_0_18")
			(pintype "bidirectional")
			(die_length 15.365)
			(solder_mask_margin 0.02)
		)
		(pad "G13" smd circle
			(at -2.5 -8.5)
			(size 0.5 0.5)
			(property pad_prop_bga)
			(layers "F.Cu" "F.Mask" "F.Paste")
			(net 354 "/FMC+ HSPC/FMC.IO12_P")
			(pinfunction "IO_L12P_T1_MRCC_18")
			(pintype "bidirectional")
			(die_length 18.803)
			(solder_mask_margin 0.02)
		)
		(pad "G14" smd circle
			(at -1.5 -8.5)
			(size 0.5 0.5)
			(property pad_prop_bga)
			(layers "F.Cu" "F.Mask" "F.Paste")
			(net 339 "/FMC+ HSPC/FMC.IO11_N")
			(pinfunction "IO_L11N_T1_SRCC_18")
			(pintype "bidirectional")
			(die_length 18.243)
			(solder_mask_margin 0.02)
		)
		(pad "G15" smd circle
			(at -0.5 -8.5)
			(size 0.5 0.5)
			(property pad_prop_bga)
			(layers "F.Cu" "F.Mask" "F.Paste")
			(net 384 "/FMC+ HSPC/FMC.IO7_N")
			(pinfunction "IO_L7N_T1_18")
			(pintype "bidirectional")
			(die_length 15.863)
			(solder_mask_margin 0.02)
		)
		(pad "G16" smd circle
			(at 0.5 -8.5)
			(size 0.5 0.5)
			(property pad_prop_bga)
			(layers "F.Cu" "F.Mask" "F.Paste")
			(net 1 "GND")
			(pinfunction "GND")
			(pintype "passive")
			(solder_mask_margin 0.02)
		)
		(pad "G17" smd circle
			(at 1.5 -8.5)
			(size 0.5 0.5)
			(property pad_prop_bga)
			(layers "F.Cu" "F.Mask" "F.Paste")
			(net 506 "/FPGA Bank 16 & 17/GBE_RGMII.RXD0")
			(pinfunction "IO_L18P_T2_17")
			(pintype "bidirectional")
			(die_length 20.206)
			(solder_mask_margin 0.02)
		)
		(pad "G18" smd circle
			(at 2.5 -8.5)
			(size 0.5 0.5)
			(property pad_prop_bga)
			(layers "F.Cu" "F.Mask" "F.Paste")
			(net 510 "/FPGA Bank 16 & 17/GBE_RGMII.REFCLK")
			(pinfunction "IO_L16P_T2_17")
			(pintype "bidirectional")
			(die_length 20.974)
			(solder_mask_margin 0.02)
		)
		(pad "G19" smd circle
			(at 3.5 -8.5)
			(size 0.5 0.5)
			(property pad_prop_bga)
			(layers "F.Cu" "F.Mask" "F.Paste")
			(net 695 "/FMC+ HSPC/FMC.~{PERST}")
			(pinfunction "IO_0_17")
			(pintype "bidirectional")
			(die_length 9.384)
			(solder_mask_margin 0.02)
		)
		(pad "G20" smd circle
			(at 4.5 -8.5)
			(size 0.5 0.5)
			(property pad_prop_bga)
			(layers "F.Cu" "F.Mask" "F.Paste")
			(net 1008 "/FPGA Bank 16 & 17/GBE_RGMII.TX_EN")
			(pinfunction "IO_L2N_T0_17")
			(pintype "bidirectional")
			(die_length 9.241)
			(solder_mask_margin 0.02)
		)
		(pad "G21" smd circle
			(at 5.5 -8.5)
			(size 0.5 0.5)
			(property pad_prop_bga)
			(layers "F.Cu" "F.Mask" "F.Paste")
			(net 24 "+3V3")
			(pinfunction "VCCO_17")
			(pintype "passive")
			(solder_mask_margin 0.02)
		)
		(pad "G22" smd circle
			(at 6.5 -8.5)
			(size 0.5 0.5)
			(property pad_prop_bga)
			(layers "F.Cu" "F.Mask" "F.Paste")
			(net 1009 "unconnected-(U1C-IO_L9P_T1_DQS_17-PadG22)")
			(pinfunction "IO_L9P_T1_DQS_17")
			(pintype "bidirectional+no_connect")
			(die_length 13.687)
			(solder_mask_margin 0.02)
		)
		(pad "G23" smd circle
			(at 7.5 -8.5)
			(size 0.5 0.5)
			(property pad_prop_bga)
			(layers "F.Cu" "F.Mask" "F.Paste")
			(net 988 "unconnected-(U1C-IO_L6P_T0_16-PadG23)")
			(pinfunction "IO_L6P_T0_16")
			(pintype "bidirectional+no_connect")
			(die_length 17.196)
			(solder_mask_margin 0.02)
		)
		(pad "G24" smd circle
			(at 8.5 -8.5)
			(size 0.5 0.5)
			(property pad_prop_bga)
			(layers "F.Cu" "F.Mask" "F.Paste")
			(net 989 "unconnected-(U1C-IO_L6N_T0_VREF_16-PadG24)")
			(pinfunction "IO_L6N_T0_VREF_16")
			(pintype "bidirectional+no_connect")
			(die_length 16.995)
			(solder_mask_margin 0.02)
		)
		(pad "G25" smd circle
			(at 9.5 -8.5)
			(size 0.5 0.5)
			(property pad_prop_bga)
			(layers "F.Cu" "F.Mask" "F.Paste")
			(net 990 "unconnected-(U1C-IO_25_16-PadG25)")
			(pinfunction "IO_25_16")
			(pintype "bidirectional+no_connect")
			(die_length 20.465)
			(solder_mask_margin 0.02)
		)
		(pad "G26" smd circle
			(at 10.5 -8.5)
			(size 0.5 0.5)
			(property pad_prop_bga)
			(layers "F.Cu" "F.Mask" "F.Paste")
			(net 1 "GND")
			(pinfunction "GND")
			(pintype "passive")
			(solder_mask_margin 0.02)
		)
		(pad "G27" smd circle
			(at 11.5 -8.5)
			(size 0.5 0.5)
			(property pad_prop_bga)
			(layers "F.Cu" "F.Mask" "F.Paste")
			(net 1293 "/USER_IO.B33")
			(pinfunction "IO_L21P_T3_DQS_16")
			(pintype "bidirectional")
			(die_length 19.597)
			(solder_mask_margin 0.02)
		)
		(pad "G28" smd circle
			(at 12.5 -8.5)
			(size 0.5 0.5)
			(property pad_prop_bga)
			(layers "F.Cu" "F.Mask" "F.Paste")
			(net 1283 "/USER_IO.B23")
			(pinfunction "IO_L20P_T3_16")
			(pintype "bidirectional")
			(die_length 19.625)
			(solder_mask_margin 0.02)
		)
		(pad "G29" smd circle
			(at 13.5 -8.5)
			(size 0.5 0.5)
			(property pad_prop_bga)
			(layers "F.Cu" "F.Mask" "F.Paste")
			(net 1279 "/USER_IO.B17")
			(pinfunction "IO_L22P_T3_16")
			(pintype "bidirectional")
			(die_length 20.638)
			(solder_mask_margin 0.02)
		)
		(pad "G30" smd circle
			(at 14.5 -8.5)
			(size 0.5 0.5)
			(property pad_prop_bga)
			(layers "F.Cu" "F.Mask" "F.Paste")
			(net 1285 "/USER_IO.B25")
			(pinfunction "IO_L24N_T3_16")
			(pintype "bidirectional")
			(die_length 20.043)
			(solder_mask_margin 0.02)
		)
		(pad "H1" smd circle
			(at -14.5 -7.5)
			(size 0.5 0.5)
			(property pad_prop_bga)
			(layers "F.Cu" "F.Mask" "F.Paste")
			(net 1010 "unconnected-(U1G-MGTXTXN2_117-PadH1)")
			(pinfunction "MGTXTXN2_117")
			(pintype "bidirectional+no_connect")
			(die_length 14.476)
			(solder_mask_margin 0.02)
		)
		(pad "H2" smd circle
			(at -13.5 -7.5)
			(size 0.5 0.5)
			(property pad_prop_bga)
			(layers "F.Cu" "F.Mask" "F.Paste")
			(net 1011 "unconnected-(U1G-MGTXTXP2_117-PadH2)")
			(pinfunction "MGTXTXP2_117")
			(pintype "bidirectional+no_connect")
			(die_length 14.439)
			(solder_mask_margin 0.02)
		)
		(pad "H3" smd circle
			(at -12.5 -7.5)
			(size 0.5 0.5)
			(property pad_prop_bga)
			(layers "F.Cu" "F.Mask" "F.Paste")
			(net 8 "+1V2_MGTAVTT")
			(pinfunction "MGTAVTT")
			(pintype "passive")
			(solder_mask_margin 0.02)
		)
		(pad "H4" smd circle
			(at -11.5 -7.5)
			(size 0.5 0.5)
			(property pad_prop_bga)
			(layers "F.Cu" "F.Mask" "F.Paste")
			(net 1 "GND")
			(pinfunction "GND")
			(pintype "passive")
			(solder_mask_margin 0.02)
		)
		(pad "H5" smd circle
			(at -10.5 -7.5)
			(size 0.5 0.5)
			(property pad_prop_bga)
			(layers "F.Cu" "F.Mask" "F.Paste")
			(net 1012 "unconnected-(U1G-MGTXRXN1_117-PadH5)")
			(pinfunction "MGTXRXN1_117")
			(pintype "bidirectional+no_connect")
			(die_length 11.235)
			(solder_mask_margin 0.02)
		)
		(pad "H6" smd circle
			(at -9.5 -7.5)
			(size 0.5 0.5)
			(property pad_prop_bga)
			(layers "F.Cu" "F.Mask" "F.Paste")
			(net 1013 "unconnected-(U1G-MGTXRXP1_117-PadH6)")
			(pinfunction "MGTXRXP1_117")
			(pintype "bidirectional+no_connect")
			(die_length 11.4)
			(solder_mask_margin 0.02)
		)
		(pad "H7" smd circle
			(at -8.5 -7.5)
			(size 0.5 0.5)
			(property pad_prop_bga)
			(layers "F.Cu" "F.Mask" "F.Paste")
			(net 6 "+1V0_MGTAVCC")
			(pinfunction "MGTAVCC")
			(pintype "passive")
			(solder_mask_margin 0.02)
		)
		(pad "H8" smd circle
			(at -7.5 -7.5)
			(size 0.5 0.5)
			(property pad_prop_bga)
			(layers "F.Cu" "F.Mask" "F.Paste")
			(net 1 "GND")
			(pinfunction "GND")
			(pintype "passive")
			(solder_mask_margin 0.02)
		)
		(pad "H9" smd circle
			(at -6.5 -7.5)
			(size 0.5 0.5)
			(property pad_prop_bga)
			(layers "F.Cu" "F.Mask" "F.Paste")
			(net 1 "GND")
			(pinfunction "GND")
			(pintype "passive")
			(solder_mask_margin 0.02)
		)
		(pad "H10" smd circle
			(at -5.5 -7.5)
			(size 0.5 0.5)
			(property pad_prop_bga)
			(layers "F.Cu" "F.Mask" "F.Paste")
			(net 220 "/FPGA Config/JTAG.TDI")
			(pinfunction "TDI_0")
			(pintype "bidirectional")
			(die_length 23.171)
			(solder_mask_margin 0.02)
		)
		(pad "H11" smd circle
			(at -4.5 -7.5)
			(size 0.5 0.5)
			(property pad_prop_bga)
			(layers "F.Cu" "F.Mask" "F.Paste")
			(net 400 "/FMC+ HSPC/FMC.IO10_P")
			(pinfunction "IO_L10P_T1_18")
			(pintype "bidirectional")
			(die_length 20.026)
			(solder_mask_margin 0.02)
		)
		(pad "H12" smd circle
			(at -3.5 -7.5)
			(size 0.5 0.5)
			(property pad_prop_bga)
			(layers "F.Cu" "F.Mask" "F.Paste")
			(net 396 "/FMC+ HSPC/FMC.IO10_N")
			(pinfunction "IO_L10N_T1_18")
			(pintype "bidirectional")
			(die_length 20.278)
			(solder_mask_margin 0.02)
		)
		(pad "H13" smd circle
			(at -2.5 -7.5)
			(size 0.5 0.5)
			(property pad_prop_bga)
			(layers "F.Cu" "F.Mask" "F.Paste")
			(net 1 "GND")
			(pinfunction "GND")
			(pintype "passive")
			(solder_mask_margin 0.02)
		)
		(pad "H14" smd circle
			(at -1.5 -7.5)
			(size 0.5 0.5)
			(property pad_prop_bga)
			(layers "F.Cu" "F.Mask" "F.Paste")
			(net 340 "/FMC+ HSPC/FMC.IO11_P")
			(pinfunction "IO_L11P_T1_SRCC_18")
			(pintype "bidirectional")
			(die_length 18.828)
			(solder_mask_margin 0.02)
		)
		(pad "H15" smd circle
			(at -0.5 -7.5)
			(size 0.5 0.5)
			(property pad_prop_bga)
			(layers "F.Cu" "F.Mask" "F.Paste")
			(net 387 "/FMC+ HSPC/FMC.IO7_P")
			(pinfunction "IO_L7P_T1_18")
			(pintype "bidirectional")
			(die_length 15.975)
			(solder_mask_margin 0.02)
		)
		(pad "H16" smd circle
			(at 0.5 -7.5)
			(size 0.5 0.5)
			(property pad_prop_bga)
			(layers "F.Cu" "F.Mask" "F.Paste")
			(net 377 "/FMC+ HSPC/FMC.IO9_N")
			(pinfunction "IO_L9N_T1_DQS_18")
			(pintype "bidirectional")
			(die_length 18.63)
			(solder_mask_margin 0.02)
		)
		(pad "H17" smd circle
			(at 1.5 -7.5)
			(size 0.5 0.5)
			(property pad_prop_bga)
			(layers "F.Cu" "F.Mask" "F.Paste")
			(net 1014 "unconnected-(U1C-IO_L3N_T0_DQS_17-PadH17)")
			(pinfunction "IO_L3N_T0_DQS_17")
			(pintype "bidirectional+no_connect")
			(die_length 10.161)
			(solder_mask_margin 0.02)
		)
		(pad "H18" smd circle
			(at 2.5 -7.5)
			(size 0.5 0.5)
			(property pad_prop_bga)
			(layers "F.Cu" "F.Mask" "F.Paste")
			(net 24 "+3V3")
			(pinfunction "VCCO_17")
			(pintype "passive")
			(solder_mask_margin 0.02)
		)
		(pad "H19" smd circle
			(at 3.5 -7.5)
			(size 0.5 0.5)
			(property pad_prop_bga)
			(layers "F.Cu" "F.Mask" "F.Paste")
			(net 696 "/FMC+ HSPC/FMC.PRSNT_M2C")
			(pinfunction "IO_L4N_T0_17")
			(pintype "bidirectional")
			(die_length 11.623)
			(solder_mask_margin 0.02)
		)
		(pad "H20" smd circle
			(at 4.5 -7.5)
			(size 0.5 0.5)
			(property pad_prop_bga)
			(layers "F.Cu" "F.Mask" "F.Paste")
			(net 1019 "/FPGA Bank 16 & 17/GBE_RGMII.GTX_CLK")
			(pinfunction "IO_L2P_T0_17")
			(pintype "bidirectional")
			(die_length 9.042)
			(solder_mask_margin 0.02)
		)
		(pad "H21" smd circle
			(at 5.5 -7.5)
			(size 0.5 0.5)
			(property pad_prop_bga)
			(layers "F.Cu" "F.Mask" "F.Paste")
			(net 1021 "/FPGA Bank 16 & 17/GBE_RGMII.TXD1")
			(pinfunction "IO_L7P_T1_17")
			(pintype "bidirectional")
			(die_length 11.269)
			(solder_mask_margin 0.02)
		)
		(pad "H22" smd circle
			(at 6.5 -7.5)
			(size 0.5 0.5)
			(property pad_prop_bga)
			(layers "F.Cu" "F.Mask" "F.Paste")
			(net 1022 "unconnected-(U1C-IO_L7N_T1_17-PadH22)")
			(pinfunction "IO_L7N_T1_17")
			(pintype "bidirectional+no_connect")
			(die_length 11.039)
			(solder_mask_margin 0.02)
		)
		(pad "H23" smd circle
			(at 7.5 -7.5)
			(size 0.5 0.5)
			(property pad_prop_bga)
			(layers "F.Cu" "F.Mask" "F.Paste")
			(net 1 "GND")
			(pinfunction "GND")
			(pintype "passive")
			(solder_mask_margin 0.02)
		)
		(pad "H24" smd circle
			(at 8.5 -7.5)
			(size 0.5 0.5)
			(property pad_prop_bga)
			(layers "F.Cu" "F.Mask" "F.Paste")
			(net 1289 "/USER_IO.B29")
			(pinfunction "IO_L19P_T3_16")
			(pintype "bidirectional")
			(die_length 18.78)
			(solder_mask_margin 0.02)
		)
		(pad "H25" smd circle
			(at 9.5 -7.5)
			(size 0.5 0.5)
			(property pad_prop_bga)
			(layers "F.Cu" "F.Mask" "F.Paste")
			(net 1268 "/USER_IO.B5")
			(pinfunction "IO_L19N_T3_VREF_16")
			(pintype "bidirectional")
			(die_length 17.174)
			(solder_mask_margin 0.02)
		)
		(pad "H26" smd circle
			(at 10.5 -7.5)
			(size 0.5 0.5)
			(property pad_prop_bga)
			(layers "F.Cu" "F.Mask" "F.Paste")
			(net 419 "/FPGA Bank 16 & 17/USR_FLASH_1.DQ2")
			(pinfunction "IO_L23P_T3_16")
			(pintype "bidirectional")
			(die_length 18.226)
			(solder_mask_margin 0.02)
		)
	)
)
